FILE_TYPE = CONNECTIVITY;
{Allegro Design Entry HDL 16.6-p007 (v16-6-112F) 10/10/2012}
"PAGE_NUMBER" = 91;
0"NC";
1"GND\g";
2"PVPP_ABC\g";
3"PVPP_ABC\g";
4"PVPP_ABC\g";
5"P3V3\g";
6"GND\g";
7"SMB_OCP_FRU_STBY_LVC3_SDA";
8"IRQ_HFI1_CPU0_LVT2_N";
9"LED_HFI0_CPU0_N";
10"TP_HFI_IO_CONN0_RSVD_17";
11"FM_MODPRST_HFI1_CPU0_LVT2_N";
12"PWRGD_PVPP_ABC";
13"SMB_OCP_FRU_STBY_LVC3_SCL";
14"RST_HFI0_CPU0_LVT2_N";
15"SMB_HFI1_CPU0_LVC2_SDA";
16"SMB_HFI1_CPU0_LVC2_SCL";
17"IRQ_HFI0_CPU0_LVT2_N";
18"RST_HFI1_CPU0_LVT2_N";
19"SMB_HFI0_CPU0_LVC2_SDA";
20"SMB_HFI0_CPU0_LVC2_SCL";
21"LED_HFI1_CPU0_N";
22"FM_MODPRST_HFI0_CPU0_LVT2_N";
%"SCONN24_H46321001"
"1","(-125,2850)","0","mstr_sconn","I1";
;
LOCATION"J8B1"
PART_NUMBER"H46321-001"
MATERIAL"SCONN"
PACK_TYPE"SM"
CDS_LIB"mstr_sconn"
CDS_SEC"1"
$SEC"1"
CDS_LOCATION"J8B1"
ROOM"HFI";
"MP1"
$PN"MP1"1;
"MP2"
$PN"MP2"6;
"IO1"
$PN"1"1;
"IO10"
$PN"10"16;
"IO11"
$PN"11"11;
"IO12"
$PN"12"15;
"IO13"
$PN"13"21;
"IO14"
$PN"14"18;
"IO15"
$PN"15"1;
"IO16"
$PN"16"8;
"IO17"
$PN"17"10;
"IO18"
$PN"18"5;
"IO19"
$PN"19"12;
"IO2"
$PN"2"20;
"IO20"
$PN"20"5;
"IO21"
$PN"21"3;
"IO22"
$PN"22"13;
"IO23"
$PN"23"1;
"IO24"
$PN"24"7;
"IO3"
$PN"3"22;
"IO4"
$PN"4"19;
"IO5"
$PN"5"9;
"IO6"
$PN"6"14;
"IO7"
$PN"7"1;
"IO8"
$PN"8"17;
"IO9"
$PN"9"1;
%"RES"
"2","(1250,3375)","0","mstr_discrete","I14";
;
CDS_SEC"1"
LOCATION"R8B8"
PART_NUMBER"G21796-072"
VALUE"4.75K"
PACK_TYPE"0402"
WATTAGE"1/16W"
MATERIAL"CHIP"
TOLERANCE"1%"
CDS_LIB"mstr_discrete"
SEC_TYPE"0402"
SIGNAL_MODEL"DEFAULT_RESISTOR_4750OHM_2_1"
SEC"1"
CDS_LOCATION"R8B8"
ROOM"HFI";
"A"
$PN"1"4;
"B"
$PN"2"14;
%"RES"
"2","(1000,3375)","0","mstr_discrete","I16";
;
CDS_SEC"1"
LOCATION"R8B10"
VALUE"4.75K"
TOLERANCE"1%"
PACK_TYPE"0402"
PART_NUMBER"G21796-072"
MATERIAL"CHIP"
WATTAGE"1/16W"
CDS_LIB"mstr_discrete"
SEC_TYPE"0402"
SIGNAL_MODEL"DEFAULT_RESISTOR_4750OHM_2_1"
SEC"1"
CDS_LOCATION"R8B10"
ROOM"HFI";
"A"
$PN"1"4;
"B"
$PN"2"17;
%"RES"
"2","(750,3375)","0","mstr_discrete","I17";
;
CDS_SEC"1"
LOCATION"R8B16"
VALUE"4.75K"
TOLERANCE"1%"
MATERIAL"CHIP"
WATTAGE"1/16W"
PACK_TYPE"0402"
PART_NUMBER"G21796-072"
CDS_LIB"mstr_discrete"
SEC_TYPE"0402"
SIGNAL_MODEL"DEFAULT_RESISTOR_4750OHM_2_1"
SEC"1"
CDS_LOCATION"R8B16"
ROOM"HFI";
"A"
$PN"1"4;
"B"
$PN"2"18;
%"RES"
"2","(500,3375)","0","mstr_discrete","I18";
;
CDS_SEC"1"
LOCATION"R8B17"
PART_NUMBER"G21796-072"
VALUE"4.75K"
TOLERANCE"1%"
PACK_TYPE"0402"
MATERIAL"CHIP"
WATTAGE"1/16W"
SIGNAL_MODEL"DEFAULT_RESISTOR_4750OHM_2_1"
SEC_TYPE"0402"
CDS_LIB"mstr_discrete"
SEC"1"
CDS_LOCATION"R8B17"
ROOM"HFI";
"A"
$PN"1"4;
"B"
$PN"2"8;
%"GND"
"1","(-625,2350)","0","mstr_symbols","I2";
;
VOLTAGE"0.0V"
CDS_LIB"mstr_symbols"
SIZE"1B"
BODY_TYPE"PLUMBING"
HDL_POWER"GND";
"A\NAC"1;
%"RES"
"2","(-750,3350)","2","mstr_discrete","I20";
;
CDS_SEC"1"
LOCATION"R8B18"
PART_NUMBER"G21796-072"
VALUE"4.75K"
TOLERANCE"1%"
MATERIAL"CHIP"
WATTAGE"1/16W"
PACK_TYPE"0402"
SIGNAL_MODEL"DEFAULT_RESISTOR_4750OHM_2_1"
CDS_LIB"mstr_discrete"
SEC_TYPE"0402"
SEC"1"
CDS_LOCATION"R8B18"
ROOM"HFI";
"A"
$PN"1"2;
"B"
$PN"2"21;
%"RES"
"2","(-1125,3350)","2","mstr_discrete","I21";
;
CDS_SEC"1"
LOCATION"R8B19"
PART_NUMBER"G21796-072"
TOLERANCE"1%"
PACK_TYPE"0402"
MATERIAL"CHIP"
WATTAGE"1/16W"
VALUE"4.75K"
SIGNAL_MODEL"DEFAULT_RESISTOR_4750OHM_2_1"
CDS_LIB"mstr_discrete"
SEC_TYPE"0402"
SEC"1"
CDS_LOCATION"R8B19"
ROOM"HFI";
"A"
$PN"1"2;
"B"
$PN"2"11;
%"RES"
"2","(-1500,3350)","2","mstr_discrete","I22";
;
CDS_SEC"1"
LOCATION"R8B5"
PART_NUMBER"G21796-072"
VALUE"4.75K"
TOLERANCE"1%"
PACK_TYPE"0402"
MATERIAL"CHIP"
WATTAGE"1/16W"
SIGNAL_MODEL"DEFAULT_RESISTOR_4750OHM_2_1"
CDS_LIB"mstr_discrete"
SEC_TYPE"0402"
SEC"1"
CDS_LOCATION"R8B5"
ROOM"HFI";
"A"
$PN"1"2;
"B"
$PN"2"9;
%"RES"
"2","(-1875,3350)","2","mstr_discrete","I24";
;
CDS_SEC"1"
LOCATION"R8B3"
PART_NUMBER"G21796-072"
VALUE"4.75K"
TOLERANCE"1%"
PACK_TYPE"0402"
MATERIAL"CHIP"
WATTAGE"1/16W"
SIGNAL_MODEL"DEFAULT_RESISTOR_4750OHM_2_1"
CDS_LIB"mstr_discrete"
SEC_TYPE"0402"
SEC"1"
CDS_LOCATION"R8B3"
ROOM"HFI";
"A"
$PN"1"2;
"B"
$PN"2"22;
%"PVPP_ABC"
"1","(-1875,3650)","0","mstr_symbols","I30";
;
VOLTAGE"2.5V"
BOM_COST"PVPP_KLM_VR"
CDS_LIB"mstr_symbols"
ROOM"PVPP_KLM_VR"
BODY_TYPE"PLUMBING"
HDL_POWER"PVPP_ABC";
"G\NAC"2;
%"PVPP_ABC"
"1","(-675,3650)","0","mstr_symbols","I31";
;
VOLTAGE"2.5V"
BOM_COST"PVPP_KLM_VR"
CDS_LIB"mstr_symbols"
ROOM"PVPP_KLM_VR"
BODY_TYPE"PLUMBING"
HDL_POWER"PVPP_ABC";
"G\NAC"3;
%"PVPP_ABC"
"1","(2250,3700)","0","mstr_symbols","I32";
;
VOLTAGE"2.5V"
BOM_COST"PVPP_KLM_VR"
CDS_LIB"mstr_symbols"
ROOM"PVPP_KLM_VR"
BODY_TYPE"PLUMBING"
HDL_POWER"PVPP_ABC";
"G\NAC"4;
%"P3V3"
"1","(425,3650)","0","mstr_symbols","I33";
;
VOLTAGE"3.3V"
CDS_LIB"mstr_symbols"
SIZE"1B"
BODY_TYPE"PLUMBING"
HDL_POWER"P3V3";
"G\NAC"5;
%"RES"
"2","(1500,3375)","0","mstr_discrete","I34";
;
CDS_SEC"1"
LOCATION"R8B13"
PART_NUMBER"G21796-336"
VALUE"1.8K"
TOLERANCE"1%"
PACK_TYPE"0402"
MATERIAL"CHIP"
WATTAGE"1/16W"
CDS_LIB"mstr_discrete"
SEC_TYPE"0402"
SEC"1"
CDS_LOCATION"R8B13"
ROOM"SMBUS_CPU0_STL";
"A"
$PN"1"4;
"B"
$PN"2"15;
%"RES"
"2","(1725,3375)","0","mstr_discrete","I35";
;
CDS_SEC"1"
LOCATION"R8B11"
PART_NUMBER"G21796-336"
VALUE"1.8K"
TOLERANCE"1%"
PACK_TYPE"0402"
MATERIAL"CHIP"
WATTAGE"1/16W"
CDS_LIB"mstr_discrete"
SEC_TYPE"0402"
SEC"1"
CDS_LOCATION"R8B11"
ROOM"SMBUS_CPU0_STL";
"A"
$PN"1"4;
"B"
$PN"2"16;
%"RES"
"2","(1975,3375)","0","mstr_discrete","I36";
;
CDS_SEC"1"
LOCATION"R8B7"
PART_NUMBER"G21796-336"
VALUE"1.8K"
TOLERANCE"1%"
PACK_TYPE"0402"
MATERIAL"CHIP"
WATTAGE"1/16W"
CDS_LIB"mstr_discrete"
SEC_TYPE"0402"
SEC"1"
CDS_LOCATION"R8B7"
ROOM"SMBUS_CPU0_STL";
"A"
$PN"1"4;
"B"
$PN"2"19;
%"RES"
"2","(2250,3375)","0","mstr_discrete","I37";
;
CDS_SEC"1"
LOCATION"R8B6"
PART_NUMBER"G21796-336"
VALUE"1.8K"
TOLERANCE"1%"
PACK_TYPE"0402"
MATERIAL"CHIP"
WATTAGE"1/16W"
CDS_LIB"mstr_discrete"
SEC_TYPE"0402"
SEC"1"
CDS_LOCATION"R8B6"
ROOM"SMBUS_CPU0_STL";
"A"
$PN"1"4;
"B"
$PN"2"20;
%"GND"
"1","(375,2350)","0","mstr_symbols","I38";
;
VOLTAGE"0.0V"
SIZE"1B"
CDS_LIB"mstr_symbols"
BODY_TYPE"PLUMBING"
HDL_POWER"GND";
"A\NAC"6;
END.
